# T6G (Grand Teton) — schematic netlist excerpt (pin names and nets, part order shuffled) for the footprints in the layout excerpt that follows; sources: Cadence DE-HDL packaged netlist, KiCad conversion of 04192023_DAF0TMB3IC0_F0TG_MB_C_brd_V02_OCP.brd

PR2538  Q_RES  10 1% CHIP  pkg 0402LF  page 266 : A = MB0_CM_GATE_G0 ; B = P12V_HSC_GATE1
C949  Q_CAP_DIFFBUS  DIFF BUS_0.22UF 6.3V 20% X6S  pkg C0201  page 63 : \1\ = P5E_CPU0_P1_TX_C_DP<8> ; \2\ = P5E_CPU0_P1_TX_DP<8>
R1640  Q_RES  22 1% CHIP  pkg 0402LF  page 173 : A = JTAG_P0_R_TRST_N ; B = JTAG_CPU0_TRST_N

(kicad_pcb
	(version 20260206)
	(generator "pcbnew")
	(generator_version "10.0")
	(general
		(thickness 1.6)
		(legacy_teardrops no)
	)
	(paper "A4")
	(title_block
		(title "04192023_DAF0TMB3IC0_F0TG_MB_C_brd_V02_OCP.brd")
		(comment 1 "Grand Teton / footprints 4836-4838 of 8354")
	)
	(layers
		(0 "F.Cu" signal "TOP")
		(4 "In1.Cu" signal "GND")
		(6 "In2.Cu" signal "IN1")
		(8 "In3.Cu" signal "GND1")
		(10 "In4.Cu" signal "IN2")
		(12 "In5.Cu" signal "GND2")
		(14 "In6.Cu" signal "IN3")
		(16 "In7.Cu" signal "GND3")
		(18 "In8.Cu" signal "VCC")
		(20 "In9.Cu" signal "VCC1")
		(22 "In10.Cu" signal "GND4")
		(24 "In11.Cu" signal "IN4")
		(26 "In12.Cu" signal "GND5")
		(28 "In13.Cu" signal "IN5")
		(30 "In14.Cu" signal "GND6")
		(32 "In15.Cu" signal "IN6")
		(34 "In16.Cu" signal "GND7")
		(2 "B.Cu" signal "BOTTOM")
		(9 "F.Adhes" user "F.Adhesive")
		(11 "B.Adhes" user "B.Adhesive")
		(13 "F.Paste" user "Package Geometry/Pastemask Top")
		(15 "B.Paste" user "Package Geometry/Pastemask Bottom")
		(5 "F.SilkS" user "Ref Des/Silkscreen Top")
		(7 "B.SilkS" user "Ref Des/Silkscreen Bottom")
		(1 "F.Mask" user "Board Geometry/Soldermask Top")
		(3 "B.Mask" user "Board Geometry/Soldermask Bottom")
		(17 "Dwgs.User" user "User.Drawings")
		(19 "Cmts.User" user "User.Comments")
		(21 "Eco1.User" user "User.Eco1")
		(23 "Eco2.User" user "User.Eco2")
		(25 "Edge.Cuts" user "Board Geometry/Outline")
		(27 "Margin" user)
		(31 "F.CrtYd" user "Package Geometry/Place Bound Top")
		(29 "B.CrtYd" user "Package Geometry/Place Bound Bottom")
		(35 "F.Fab" user "Ref Des/Assembly Top")
		(33 "B.Fab" user "Ref Des/Assembly Bottom")
	)
	(footprint ""
		(layer "F.Cu")
		(at 279.570942 -380.66853)
		(property "Reference" "PR2538"
			(at 0 0 0)
			(layer "F.SilkS")
			(hide yes)
			(effects
				(font
					(size 1.27 1.27)
				)
			)
		)
		(property "Value" ""
			(at 0 0 0)
			(layer "F.Fab")
			(effects
				(font
					(size 1.27 1.27)
				)
			)
		)
		(duplicate_pad_numbers_are_jumpers no)
		(fp_line
			(start -0.7874 -0.4064)
			(end 0.7874 -0.4064)
			(stroke
				(width 0.1524)
				(type default)
			)
			(layer "F.SilkS")
		)
		(fp_line
			(start -0.7874 0.4064)
			(end -0.7874 -0.4064)
			(stroke
				(width 0.1524)
				(type default)
			)
			(layer "F.SilkS")
		)
		(fp_line
			(start 0.7874 -0.4064)
			(end 0.7874 0.4064)
			(stroke
				(width 0.1524)
				(type default)
			)
			(layer "F.SilkS")
		)
		(fp_line
			(start 0.7874 0.4064)
			(end -0.7874 0.4064)
			(stroke
				(width 0.1524)
				(type default)
			)
			(layer "F.SilkS")
		)
		(fp_line
			(start -0.67945 -0.305054)
			(end -0.12065 -0.305054)
			(stroke
				(width 0.1)
				(type default)
			)
			(layer "F.Fab")
		)
		(fp_line
			(start -0.67945 0.3048)
			(end -0.67945 -0.305054)
			(stroke
				(width 0.1)
				(type default)
			)
			(layer "F.Fab")
		)
		(fp_line
			(start -0.12065 -0.305054)
			(end -0.12065 -0.2794)
			(stroke
				(width 0.1)
				(type default)
			)
			(layer "F.Fab")
		)
		(fp_line
			(start -0.12065 -0.2794)
			(end 0.12065 -0.2794)
			(stroke
				(width 0.1)
				(type default)
			)
			(layer "F.Fab")
		)
		(fp_line
			(start -0.12065 0.2794)
			(end -0.12065 0.3048)
			(stroke
				(width 0.1)
				(type default)
			)
			(layer "F.Fab")
		)
		(fp_line
			(start -0.12065 0.3048)
			(end -0.67945 0.3048)
			(stroke
				(width 0.1)
				(type default)
			)
			(layer "F.Fab")
		)
		(fp_line
			(start 0.120396 0.2794)
			(end -0.12065 0.2794)
			(stroke
				(width 0.1)
				(type default)
			)
			(layer "F.Fab")
		)
		(fp_line
			(start 0.120396 0.3048)
			(end 0.120396 0.2794)
			(stroke
				(width 0.1)
				(type default)
			)
			(layer "F.Fab")
		)
		(fp_line
			(start 0.12065 -0.3048)
			(end 0.67945 -0.3048)
			(stroke
				(width 0.1)
				(type default)
			)
			(layer "F.Fab")
		)
		(fp_line
			(start 0.12065 -0.2794)
			(end 0.12065 -0.3048)
			(stroke
				(width 0.1)
				(type default)
			)
			(layer "F.Fab")
		)
		(fp_line
			(start 0.67945 -0.3048)
			(end 0.67945 0.3048)
			(stroke
				(width 0.1)
				(type default)
			)
			(layer "F.Fab")
		)
		(fp_line
			(start 0.67945 0.3048)
			(end 0.120396 0.3048)
			(stroke
				(width 0.1)
				(type default)
			)
			(layer "F.Fab")
		)
		(pad "1" smd circle
			(at -0.40005 0)
			(size 0 0)
			(layers "F.Cu" "F.Mask" "F.Paste")
			(net "MB0_CM_GATE_G0")
		)
		(pad "2" smd circle
			(at 0.40005 0)
			(size 0 0)
			(layers "F.Cu" "F.Mask" "F.Paste")
			(net "P12V_HSC_GATE1")
		)
	)
	(footprint ""
		(layer "F.Cu")
		(at 252.08484 -92.719144 -90)
		(property "Reference" "R1640"
			(at 0 0 270)
			(layer "F.SilkS")
			(hide yes)
			(effects
				(font
					(size 1.27 1.27)
				)
			)
		)
		(property "Value" ""
			(at 0 0 270)
			(layer "F.Fab")
			(effects
				(font
					(size 1.27 1.27)
				)
			)
		)
		(duplicate_pad_numbers_are_jumpers no)
		(fp_line
			(start -0.7874 0.4064)
			(end -0.7874 -0.4064)
			(stroke
				(width 0.1524)
				(type default)
			)
			(layer "F.SilkS")
		)
		(fp_line
			(start 0.7874 0.4064)
			(end -0.7874 0.4064)
			(stroke
				(width 0.1524)
				(type default)
			)
			(layer "F.SilkS")
		)
		(fp_line
			(start -0.7874 -0.4064)
			(end 0.7874 -0.4064)
			(stroke
				(width 0.1524)
				(type default)
			)
			(layer "F.SilkS")
		)
		(fp_line
			(start 0.7874 -0.4064)
			(end 0.7874 0.4064)
			(stroke
				(width 0.1524)
				(type default)
			)
			(layer "F.SilkS")
		)
		(fp_line
			(start -0.67945 0.3048)
			(end -0.67945 -0.305054)
			(stroke
				(width 0.1)
				(type default)
			)
			(layer "F.Fab")
		)
		(fp_line
			(start -0.12065 0.3048)
			(end -0.67945 0.3048)
			(stroke
				(width 0.1)
				(type default)
			)
			(layer "F.Fab")
		)
		(fp_line
			(start 0.120396 0.3048)
			(end 0.120396 0.2794)
			(stroke
				(width 0.1)
				(type default)
			)
			(layer "F.Fab")
		)
		(fp_line
			(start 0.67945 0.3048)
			(end 0.120396 0.3048)
			(stroke
				(width 0.1)
				(type default)
			)
			(layer "F.Fab")
		)
		(fp_line
			(start -0.12065 0.2794)
			(end -0.12065 0.3048)
			(stroke
				(width 0.1)
				(type default)
			)
			(layer "F.Fab")
		)
		(fp_line
			(start 0.120396 0.2794)
			(end -0.12065 0.2794)
			(stroke
				(width 0.1)
				(type default)
			)
			(layer "F.Fab")
		)
		(fp_line
			(start -0.12065 -0.2794)
			(end 0.12065 -0.2794)
			(stroke
				(width 0.1)
				(type default)
			)
			(layer "F.Fab")
		)
		(fp_line
			(start 0.12065 -0.2794)
			(end 0.12065 -0.3048)
			(stroke
				(width 0.1)
				(type default)
			)
			(layer "F.Fab")
		)
		(fp_line
			(start 0.12065 -0.3048)
			(end 0.67945 -0.3048)
			(stroke
				(width 0.1)
				(type default)
			)
			(layer "F.Fab")
		)
		(fp_line
			(start 0.67945 -0.3048)
			(end 0.67945 0.3048)
			(stroke
				(width 0.1)
				(type default)
			)
			(layer "F.Fab")
		)
		(fp_line
			(start -0.67945 -0.305054)
			(end -0.12065 -0.305054)
			(stroke
				(width 0.1)
				(type default)
			)
			(layer "F.Fab")
		)
		(fp_line
			(start -0.12065 -0.305054)
			(end -0.12065 -0.2794)
			(stroke
				(width 0.1)
				(type default)
			)
			(layer "F.Fab")
		)
		(pad "1" smd circle
			(at -0.40005 0 270)
			(size 0 0)
			(layers "F.Cu" "F.Mask" "F.Paste")
			(net "JTAG_P0_R_TRST_N")
		)
		(pad "2" smd circle
			(at 0.40005 0 270)
			(size 0 0)
			(layers "F.Cu" "F.Mask" "F.Paste")
			(net "JTAG_CPU0_TRST_N")
		)
	)
	(footprint ""
		(layer "F.Cu")
		(at 345.131644 -381.41783 -90)
		(property "Reference" "C949"
			(at 0 0 270)
			(layer "F.SilkS")
			(hide yes)
			(effects
				(font
					(size 1.27 1.27)
				)
			)
		)
		(property "Value" ""
			(at 0 0 270)
			(layer "F.Fab")
			(effects
				(font
					(size 1.27 1.27)
				)
			)
		)
		(duplicate_pad_numbers_are_jumpers no)
		(fp_line
			(start -0.299974 0.150114)
			(end -0.299974 -0.150114)
			(stroke
				(width 0.1)
				(type default)
			)
			(layer "F.Fab")
		)
		(fp_line
			(start 0.299974 0.150114)
			(end -0.299974 0.150114)
			(stroke
				(width 0.1)
				(type default)
			)
			(layer "F.Fab")
		)
		(fp_line
			(start -0.299974 -0.150114)
			(end 0.299974 -0.150114)
			(stroke
				(width 0.1)
				(type default)
			)
			(layer "F.Fab")
		)
		(fp_line
			(start 0.299974 -0.150114)
			(end 0.299974 0.150114)
			(stroke
				(width 0.1)
				(type default)
			)
			(layer "F.Fab")
		)
		(pad "1" smd rect
			(at -0.2667 0 270)
			(size 0.3048 0.381)
			(layers "F.Cu" "F.Mask" "F.Paste")
			(net "P5E_CPU0_P1_TX_C_DP<8>")
		)
		(pad "2" smd rect
			(at 0.2667 0 270)
			(size 0.3048 0.381)
			(layers "F.Cu" "F.Mask" "F.Paste")
			(net "P5E_CPU0_P1_TX_DP<8>")
		)
	)
)
